# T6G (Grand Teton) — schematic netlist excerpt (pin names and nets, part order shuffled) for the footprints in the layout excerpt that follows; sources: Cadence DE-HDL packaged netlist, KiCad conversion of 04192023_DAF0TMB3IC0_F0TG_MB_C_brd_V02_OCP.brd

PR41  Q_RES  1K 1% EMPTY  pkg 0402LF  page 200 : A = PVDD18_S5_P0 ; B = SVID_PVDDCR_CPU1_P0_SVTI
PC244  Q_CAP  3300PF 50V 10% X7R  pkg 0402  page 210 : A = VSENSE_PVDDCR_CPU0_P1_VSEN0 ; B = VSENSE_VSS_SENSE_A_P1

(kicad_pcb
	(version 20260206)
	(generator "pcbnew")
	(generator_version "10.0")
	(general
		(thickness 1.6)
		(legacy_teardrops no)
	)
	(paper "A4")
	(title_block
		(title "04192023_DAF0TMB3IC0_F0TG_MB_C_brd_V02_OCP.brd")
		(comment 1 "Grand Teton / footprints 6882-6883 of 8354")
	)
	(layers
		(0 "F.Cu" signal "TOP")
		(4 "In1.Cu" signal "GND")
		(6 "In2.Cu" signal "IN1")
		(8 "In3.Cu" signal "GND1")
		(10 "In4.Cu" signal "IN2")
		(12 "In5.Cu" signal "GND2")
		(14 "In6.Cu" signal "IN3")
		(16 "In7.Cu" signal "GND3")
		(18 "In8.Cu" signal "VCC")
		(20 "In9.Cu" signal "VCC1")
		(22 "In10.Cu" signal "GND4")
		(24 "In11.Cu" signal "IN4")
		(26 "In12.Cu" signal "GND5")
		(28 "In13.Cu" signal "IN5")
		(30 "In14.Cu" signal "GND6")
		(32 "In15.Cu" signal "IN6")
		(34 "In16.Cu" signal "GND7")
		(2 "B.Cu" signal "BOTTOM")
		(9 "F.Adhes" user "F.Adhesive")
		(11 "B.Adhes" user "B.Adhesive")
		(13 "F.Paste" user "Package Geometry/Pastemask Top")
		(15 "B.Paste" user "Package Geometry/Pastemask Bottom")
		(5 "F.SilkS" user "Ref Des/Silkscreen Top")
		(7 "B.SilkS" user "Ref Des/Silkscreen Bottom")
		(1 "F.Mask" user "Board Geometry/Soldermask Top")
		(3 "B.Mask" user "Board Geometry/Soldermask Bottom")
		(17 "Dwgs.User" user "User.Drawings")
		(19 "Cmts.User" user "User.Comments")
		(21 "Eco1.User" user "User.Eco1")
		(23 "Eco2.User" user "User.Eco2")
		(25 "Edge.Cuts" user "Board Geometry/Outline")
		(27 "Margin" user)
		(31 "F.CrtYd" user "Package Geometry/Place Bound Top")
		(29 "B.CrtYd" user "Package Geometry/Place Bound Bottom")
		(35 "F.Fab" user "Ref Des/Assembly Top")
		(33 "B.Fab" user "Ref Des/Assembly Bottom")
	)
	(footprint ""
		(layer "B.Cu")
		(at 92.350082 -149.981666 180)
		(property "Reference" "PC244"
			(at 0 0 0)
			(layer "B.SilkS")
			(hide yes)
			(effects
				(font
					(size 1.27 1.27)
				)
				(justify mirror)
			)
		)
		(property "Value" ""
			(at 0 0 0)
			(layer "B.Fab")
			(effects
				(font
					(size 1.27 1.27)
				)
				(justify mirror)
			)
		)
		(duplicate_pad_numbers_are_jumpers no)
		(fp_line
			(start 0.7874 0.4064)
			(end 0.7874 -0.4064)
			(stroke
				(width 0.1524)
				(type default)
			)
			(layer "B.SilkS")
		)
		(fp_line
			(start 0.7874 -0.4064)
			(end -0.7874 -0.4064)
			(stroke
				(width 0.1524)
				(type default)
			)
			(layer "B.SilkS")
		)
		(fp_line
			(start -0.7874 0.4064)
			(end 0.7874 0.4064)
			(stroke
				(width 0.1524)
				(type default)
			)
			(layer "B.SilkS")
		)
		(fp_line
			(start -0.7874 -0.4064)
			(end -0.7874 0.4064)
			(stroke
				(width 0.1524)
				(type default)
			)
			(layer "B.SilkS")
		)
		(fp_line
			(start 0.67945 0.3048)
			(end 0.67945 -0.305054)
			(stroke
				(width 0.1)
				(type default)
			)
			(layer "B.Fab")
		)
		(fp_line
			(start 0.67945 -0.305054)
			(end 0.12065 -0.305054)
			(stroke
				(width 0.1)
				(type default)
			)
			(layer "B.Fab")
		)
		(fp_line
			(start 0.12065 0.3048)
			(end 0.67945 0.3048)
			(stroke
				(width 0.1)
				(type default)
			)
			(layer "B.Fab")
		)
		(fp_line
			(start 0.12065 0.2794)
			(end 0.12065 0.3048)
			(stroke
				(width 0.1)
				(type default)
			)
			(layer "B.Fab")
		)
		(fp_line
			(start 0.12065 -0.2794)
			(end -0.12065 -0.2794)
			(stroke
				(width 0.1)
				(type default)
			)
			(layer "B.Fab")
		)
		(fp_line
			(start 0.12065 -0.305054)
			(end 0.12065 -0.2794)
			(stroke
				(width 0.1)
				(type default)
			)
			(layer "B.Fab")
		)
		(fp_line
			(start -0.120396 0.3048)
			(end -0.120396 0.2794)
			(stroke
				(width 0.1)
				(type default)
			)
			(layer "B.Fab")
		)
		(fp_line
			(start -0.120396 0.2794)
			(end 0.12065 0.2794)
			(stroke
				(width 0.1)
				(type default)
			)
			(layer "B.Fab")
		)
		(fp_line
			(start -0.12065 -0.2794)
			(end -0.12065 -0.3048)
			(stroke
				(width 0.1)
				(type default)
			)
			(layer "B.Fab")
		)
		(fp_line
			(start -0.12065 -0.3048)
			(end -0.67945 -0.3048)
			(stroke
				(width 0.1)
				(type default)
			)
			(layer "B.Fab")
		)
		(fp_line
			(start -0.67945 0.3048)
			(end -0.120396 0.3048)
			(stroke
				(width 0.1)
				(type default)
			)
			(layer "B.Fab")
		)
		(fp_line
			(start -0.67945 -0.3048)
			(end -0.67945 0.3048)
			(stroke
				(width 0.1)
				(type default)
			)
			(layer "B.Fab")
		)
		(pad "1" smd circle
			(at 0.40005 0)
			(size 0 0)
			(layers "B.Cu" "B.Mask" "B.Paste")
			(net "VSENSE_PVDDCR_CPU0_P1_VSEN0")
		)
		(pad "2" smd circle
			(at -0.40005 0)
			(size 0 0)
			(layers "B.Cu" "B.Mask" "B.Paste")
			(net "VSENSE_VSS_SENSE_A_P1")
		)
	)
	(footprint ""
		(layer "B.Cu")
		(at 302.133 -354.711 180)
		(property "Reference" "PR41"
			(at 0 0 0)
			(layer "B.SilkS")
			(hide yes)
			(effects
				(font
					(size 1.27 1.27)
				)
				(justify mirror)
			)
		)
		(property "Value" ""
			(at 0 0 0)
			(layer "B.Fab")
			(effects
				(font
					(size 1.27 1.27)
				)
				(justify mirror)
			)
		)
		(duplicate_pad_numbers_are_jumpers no)
		(fp_line
			(start 0.7874 0.4064)
			(end 0.7874 -0.4064)
			(stroke
				(width 0.1524)
				(type default)
			)
			(layer "B.SilkS")
		)
		(fp_line
			(start 0.7874 -0.4064)
			(end -0.7874 -0.4064)
			(stroke
				(width 0.1524)
				(type default)
			)
			(layer "B.SilkS")
		)
		(fp_line
			(start -0.7874 0.4064)
			(end 0.7874 0.4064)
			(stroke
				(width 0.1524)
				(type default)
			)
			(layer "B.SilkS")
		)
		(fp_line
			(start -0.7874 -0.4064)
			(end -0.7874 0.4064)
			(stroke
				(width 0.1524)
				(type default)
			)
			(layer "B.SilkS")
		)
		(fp_line
			(start 0.67945 0.3048)
			(end 0.67945 -0.305054)
			(stroke
				(width 0.1)
				(type default)
			)
			(layer "B.Fab")
		)
		(fp_line
			(start 0.67945 -0.305054)
			(end 0.12065 -0.305054)
			(stroke
				(width 0.1)
				(type default)
			)
			(layer "B.Fab")
		)
		(fp_line
			(start 0.12065 0.3048)
			(end 0.67945 0.3048)
			(stroke
				(width 0.1)
				(type default)
			)
			(layer "B.Fab")
		)
		(fp_line
			(start 0.12065 0.2794)
			(end 0.12065 0.3048)
			(stroke
				(width 0.1)
				(type default)
			)
			(layer "B.Fab")
		)
		(fp_line
			(start 0.12065 -0.2794)
			(end -0.12065 -0.2794)
			(stroke
				(width 0.1)
				(type default)
			)
			(layer "B.Fab")
		)
		(fp_line
			(start 0.12065 -0.305054)
			(end 0.12065 -0.2794)
			(stroke
				(width 0.1)
				(type default)
			)
			(layer "B.Fab")
		)
		(fp_line
			(start -0.120396 0.3048)
			(end -0.120396 0.2794)
			(stroke
				(width 0.1)
				(type default)
			)
			(layer "B.Fab")
		)
		(fp_line
			(start -0.120396 0.2794)
			(end 0.12065 0.2794)
			(stroke
				(width 0.1)
				(type default)
			)
			(layer "B.Fab")
		)
		(fp_line
			(start -0.12065 -0.2794)
			(end -0.12065 -0.3048)
			(stroke
				(width 0.1)
				(type default)
			)
			(layer "B.Fab")
		)
		(fp_line
			(start -0.12065 -0.3048)
			(end -0.67945 -0.3048)
			(stroke
				(width 0.1)
				(type default)
			)
			(layer "B.Fab")
		)
		(fp_line
			(start -0.67945 0.3048)
			(end -0.120396 0.3048)
			(stroke
				(width 0.1)
				(type default)
			)
			(layer "B.Fab")
		)
		(fp_line
			(start -0.67945 -0.3048)
			(end -0.67945 0.3048)
			(stroke
				(width 0.1)
				(type default)
			)
			(layer "B.Fab")
		)
		(pad "1" smd circle
			(at 0.40005 0)
			(size 0 0)
			(layers "B.Cu" "B.Mask" "B.Paste")
			(net "PVDD18_S5_P0")
		)
		(pad "2" smd circle
			(at -0.40005 0)
			(size 0 0)
			(layers "B.Cu" "B.Mask" "B.Paste")
			(net "SVID_PVDDCR_CPU1_P0_SVTI")
		)
	)
)
